(kicad_pcb
	(version 20260206)
	(generator "pcbnew")
	(generator_version "10.0")
	(general
		(thickness 1.6)
		(legacy_teardrops no)
	)
	(paper "A4")
	(title_block
		(title "01162023_DA0F0TEBIF0_F0T_Expander_BD_F_brd_V02_OCP.brd")
		(comment 1 "Grand Teton / footprints 7672-7679 of 9728")
	)
	(layers
		(0 "F.Cu" signal "TOP")
		(4 "In1.Cu" signal "GND")
		(6 "In2.Cu" signal "VCC")
		(8 "In3.Cu" signal "VCC1")
		(10 "In4.Cu" signal "GND1")
		(12 "In5.Cu" signal "IN1")
		(14 "In6.Cu" signal "GND2")
		(16 "In7.Cu" signal "IN2")
		(18 "In8.Cu" signal "GND3")
		(20 "In9.Cu" signal "IN3")
		(22 "In10.Cu" signal "GND4")
		(24 "In11.Cu" signal "IN4")
		(26 "In12.Cu" signal "GND5")
		(28 "In13.Cu" signal "IN5")
		(30 "In14.Cu" signal "GND6")
		(32 "In15.Cu" signal "IN6")
		(34 "In16.Cu" signal "GND7")
		(2 "B.Cu" signal "BOTTOM")
		(9 "F.Adhes" user "F.Adhesive")
		(11 "B.Adhes" user "B.Adhesive")
		(13 "F.Paste" user "Package Geometry/Pastemask Top")
		(15 "B.Paste" user "Package Geometry/Pastemask Bottom")
		(5 "F.SilkS" user "Ref Des/Silkscreen Top")
		(7 "B.SilkS" user "Ref Des/Silkscreen Bottom")
		(1 "F.Mask" user "Board Geometry/Soldermask Top")
		(3 "B.Mask" user "Board Geometry/Soldermask Bottom")
		(17 "Dwgs.User" user "User.Drawings")
		(19 "Cmts.User" user "User.Comments")
		(21 "Eco1.User" user "User.Eco1")
		(23 "Eco2.User" user "User.Eco2")
		(25 "Edge.Cuts" user "Board Geometry/Outline")
		(27 "Margin" user)
		(31 "F.CrtYd" user "Package Geometry/Place Bound Top")
		(29 "B.CrtYd" user "Package Geometry/Place Bound Bottom")
		(35 "F.Fab" user "Ref Des/Assembly Top")
		(33 "B.Fab" user "Ref Des/Assembly Bottom")
	)
	(footprint ""
		(layer "B.Cu")
		(at 287.064704 -140.931138 180)
		(property "Reference" "U28"
			(at -0.39243 1.870964 0)
			(unlocked yes)
			(layer "B.SilkS")
			(effects
				(font
					(size 0.7874 0.5842)
					(thickness 0.1524)
				)
				(justify mirror)
			)
		)
		(property "Value" ""
			(at 0 0 0)
			(layer "B.Fab")
			(effects
				(font
					(size 1.27 1.27)
				)
				(justify mirror)
			)
		)
		(duplicate_pad_numbers_are_jumpers no)
		(fp_line
			(start 1.3462 1.1938)
			(end -1.3462 1.1938)
			(stroke
				(width 0.1524)
				(type default)
			)
			(layer "B.SilkS")
		)
		(fp_line
			(start 1.3462 -1.1938)
			(end 1.3462 1.1684)
			(stroke
				(width 0.1524)
				(type default)
			)
			(layer "B.SilkS")
		)
		(fp_line
			(start -1.3462 1.1938)
			(end -1.3462 -1.1938)
			(stroke
				(width 0.1524)
				(type default)
			)
			(layer "B.SilkS")
		)
		(fp_line
			(start -1.3462 -1.1938)
			(end 1.3462 -1.1938)
			(stroke
				(width 0.1524)
				(type default)
			)
			(layer "B.SilkS")
		)
		(fp_poly
			(pts
				(xy 1.447038 -0.760476) (xy 2.052066 -0.457962) (xy 2.052066 -1.06299)
			)
			(stroke
				(width 0)
				(type default)
			)
			(fill yes)
			(layer "B.SilkS")
		)
		(fp_line
			(start 0.674878 1.124966)
			(end -0.674878 1.124966)
			(stroke
				(width 0.1)
				(type default)
			)
			(layer "B.Fab")
		)
		(fp_line
			(start 0.674878 -1.124966)
			(end 0.674878 1.124966)
			(stroke
				(width 0.1)
				(type default)
			)
			(layer "B.Fab")
		)
		(fp_line
			(start -0.674878 1.124966)
			(end -0.674878 -1.124966)
			(stroke
				(width 0.1)
				(type default)
			)
			(layer "B.Fab")
		)
		(fp_line
			(start -0.674878 -1.124966)
			(end 0.674878 -1.124966)
			(stroke
				(width 0.1)
				(type default)
			)
			(layer "B.Fab")
		)
		(fp_poly
			(pts
				(xy 1.447038 -0.760476) (xy 2.052066 -0.457962) (xy 2.052066 -1.06299)
			)
			(stroke
				(width 0)
				(type default)
			)
			(fill yes)
			(layer "B.Fab")
		)
		(pad "1" smd rect
			(at 0.899922 -0.750062)
			(size 0.6096 0.6096)
			(layers "B.Cu" "B.Mask" "B.Paste")
			(net "NIC4_AUX_PWR_EN_R")
		)
		(pad "2" smd rect
			(at 0.899922 0 270)
			(size 0.4064 0.6096)
			(layers "B.Cu" "B.Mask" "B.Paste")
			(net "RST_SMB_NIC4_MUX_N")
		)
		(pad "3" smd rect
			(at 0.899922 0.750062)
			(size 0.6096 0.6096)
			(layers "B.Cu" "B.Mask" "B.Paste")
			(net "GND")
		)
		(pad "4" smd rect
			(at -0.899922 0.750062)
			(size 0.6096 0.6096)
			(layers "B.Cu" "B.Mask" "B.Paste")
			(net "RST_SMB_NIC4_MUX_ISO_N")
		)
		(pad "5" smd rect
			(at -0.899922 -0.750062)
			(size 0.6096 0.6096)
			(layers "B.Cu" "B.Mask" "B.Paste")
			(net "P3V3_AUX")
		)
	)
	(footprint ""
		(layer "B.Cu")
		(at 133.018276 -308.580028 90)
		(property "Reference" "C4260"
			(at 0 0 90)
			(layer "B.SilkS")
			(hide yes)
			(effects
				(font
					(size 1.27 1.27)
				)
				(justify mirror)
			)
		)
		(property "Value" ""
			(at 0 0 90)
			(layer "B.Fab")
			(effects
				(font
					(size 1.27 1.27)
				)
				(justify mirror)
			)
		)
		(duplicate_pad_numbers_are_jumpers no)
		(fp_line
			(start 1.2954 -0.5842)
			(end -1.2954 -0.5842)
			(stroke
				(width 0.1524)
				(type default)
			)
			(layer "B.SilkS")
		)
		(fp_line
			(start -1.2954 -0.5842)
			(end -1.2954 0.5842)
			(stroke
				(width 0.1524)
				(type default)
			)
			(layer "B.SilkS")
		)
		(fp_line
			(start 1.2954 0.5842)
			(end 1.2954 -0.5842)
			(stroke
				(width 0.1524)
				(type default)
			)
			(layer "B.SilkS")
		)
		(fp_line
			(start -1.2954 0.5842)
			(end 1.2954 0.5842)
			(stroke
				(width 0.1524)
				(type default)
			)
			(layer "B.SilkS")
		)
		(fp_line
			(start 0.8636 -0.4572)
			(end -0.8636 -0.4572)
			(stroke
				(width 0.1)
				(type default)
			)
			(layer "B.Fab")
		)
		(fp_line
			(start -0.8636 -0.4572)
			(end -0.8636 -0.4064)
			(stroke
				(width 0.1)
				(type default)
			)
			(layer "B.Fab")
		)
		(fp_line
			(start 1.1938 -0.4064)
			(end 0.8636 -0.4064)
			(stroke
				(width 0.1)
				(type default)
			)
			(layer "B.Fab")
		)
		(fp_line
			(start 0.8636 -0.4064)
			(end 0.8636 -0.4572)
			(stroke
				(width 0.1)
				(type default)
			)
			(layer "B.Fab")
		)
		(fp_line
			(start -0.8636 -0.4064)
			(end -1.1938 -0.4064)
			(stroke
				(width 0.1)
				(type default)
			)
			(layer "B.Fab")
		)
		(fp_line
			(start -1.1938 -0.4064)
			(end -1.1938 0.4064)
			(stroke
				(width 0.1)
				(type default)
			)
			(layer "B.Fab")
		)
		(fp_line
			(start 1.1938 0.4064)
			(end 1.1938 -0.4064)
			(stroke
				(width 0.1)
				(type default)
			)
			(layer "B.Fab")
		)
		(fp_line
			(start 0.8636 0.4064)
			(end 1.1938 0.4064)
			(stroke
				(width 0.1)
				(type default)
			)
			(layer "B.Fab")
		)
		(fp_line
			(start -0.8636 0.4064)
			(end -0.8636 0.4572)
			(stroke
				(width 0.1)
				(type default)
			)
			(layer "B.Fab")
		)
		(fp_line
			(start -1.1938 0.4064)
			(end -0.8636 0.4064)
			(stroke
				(width 0.1)
				(type default)
			)
			(layer "B.Fab")
		)
		(fp_line
			(start 0.8636 0.4572)
			(end 0.8636 0.4064)
			(stroke
				(width 0.1)
				(type default)
			)
			(layer "B.Fab")
		)
		(fp_line
			(start -0.8636 0.4572)
			(end 0.8636 0.4572)
			(stroke
				(width 0.1)
				(type default)
			)
			(layer "B.Fab")
		)
		(pad "1" smd rect
			(at 0.7366 0)
			(size 0.7112 0.8128)
			(layers "B.Cu" "B.Mask" "B.Paste")
			(net "P0V8_PEX1")
		)
		(pad "2" smd rect
			(at -0.7366 0)
			(size 0.7112 0.8128)
			(layers "B.Cu" "B.Mask" "B.Paste")
			(net "GND")
		)
	)
	(footprint ""
		(layer "B.Cu")
		(at 228.578664 -204.44206 -90)
		(property "Reference" "R5282"
			(at 0 0 90)
			(layer "B.SilkS")
			(hide yes)
			(effects
				(font
					(size 1.27 1.27)
				)
				(justify mirror)
			)
		)
		(property "Value" ""
			(at 0 0 90)
			(layer "B.Fab")
			(effects
				(font
					(size 1.27 1.27)
				)
				(justify mirror)
			)
		)
		(duplicate_pad_numbers_are_jumpers no)
		(fp_line
			(start -0.7874 0.4064)
			(end 0.7874 0.4064)
			(stroke
				(width 0.1524)
				(type default)
			)
			(layer "B.SilkS")
		)
		(fp_line
			(start 0.7874 0.4064)
			(end 0.7874 -0.4064)
			(stroke
				(width 0.1524)
				(type default)
			)
			(layer "B.SilkS")
		)
		(fp_line
			(start -0.7874 -0.4064)
			(end -0.7874 0.4064)
			(stroke
				(width 0.1524)
				(type default)
			)
			(layer "B.SilkS")
		)
		(fp_line
			(start 0.7874 -0.4064)
			(end -0.7874 -0.4064)
			(stroke
				(width 0.1524)
				(type default)
			)
			(layer "B.SilkS")
		)
		(fp_line
			(start -0.67945 0.3048)
			(end -0.120396 0.3048)
			(stroke
				(width 0.1)
				(type default)
			)
			(layer "B.Fab")
		)
		(fp_line
			(start -0.120396 0.3048)
			(end -0.120396 0.2794)
			(stroke
				(width 0.1)
				(type default)
			)
			(layer "B.Fab")
		)
		(fp_line
			(start 0.12065 0.3048)
			(end 0.67945 0.3048)
			(stroke
				(width 0.1)
				(type default)
			)
			(layer "B.Fab")
		)
		(fp_line
			(start 0.67945 0.3048)
			(end 0.67945 -0.305054)
			(stroke
				(width 0.1)
				(type default)
			)
			(layer "B.Fab")
		)
		(fp_line
			(start -0.120396 0.2794)
			(end 0.12065 0.2794)
			(stroke
				(width 0.1)
				(type default)
			)
			(layer "B.Fab")
		)
		(fp_line
			(start 0.12065 0.2794)
			(end 0.12065 0.3048)
			(stroke
				(width 0.1)
				(type default)
			)
			(layer "B.Fab")
		)
		(fp_line
			(start -0.12065 -0.2794)
			(end -0.12065 -0.3048)
			(stroke
				(width 0.1)
				(type default)
			)
			(layer "B.Fab")
		)
		(fp_line
			(start 0.12065 -0.2794)
			(end -0.12065 -0.2794)
			(stroke
				(width 0.1)
				(type default)
			)
			(layer "B.Fab")
		)
		(fp_line
			(start -0.67945 -0.3048)
			(end -0.67945 0.3048)
			(stroke
				(width 0.1)
				(type default)
			)
			(layer "B.Fab")
		)
		(fp_line
			(start -0.12065 -0.3048)
			(end -0.67945 -0.3048)
			(stroke
				(width 0.1)
				(type default)
			)
			(layer "B.Fab")
		)
		(fp_line
			(start 0.12065 -0.305054)
			(end 0.12065 -0.2794)
			(stroke
				(width 0.1)
				(type default)
			)
			(layer "B.Fab")
		)
		(fp_line
			(start 0.67945 -0.305054)
			(end 0.12065 -0.305054)
			(stroke
				(width 0.1)
				(type default)
			)
			(layer "B.Fab")
		)
		(pad "1" smd circle
			(at 0.40005 0 90)
			(size 0 0)
			(layers "B.Cu" "B.Mask" "B.Paste")
			(net "GND")
		)
		(pad "2" smd circle
			(at -0.40005 0 90)
			(size 0 0)
			(layers "B.Cu" "B.Mask" "B.Paste")
			(net "JTAG_BIC_TCK_R")
		)
	)
	(footprint ""
		(layer "B.Cu")
		(at 186.200034 -288.774886 180)
		(property "Reference" "C3176"
			(at 0 0 0)
			(layer "B.SilkS")
			(hide yes)
			(effects
				(font
					(size 1.27 1.27)
				)
				(justify mirror)
			)
		)
		(property "Value" ""
			(at 0 0 0)
			(layer "B.Fab")
			(effects
				(font
					(size 1.27 1.27)
				)
				(justify mirror)
			)
		)
		(duplicate_pad_numbers_are_jumpers no)
		(fp_line
			(start 0.299974 0.150114)
			(end 0.299974 -0.150114)
			(stroke
				(width 0.1)
				(type default)
			)
			(layer "B.Fab")
		)
		(fp_line
			(start 0.299974 -0.150114)
			(end -0.299974 -0.150114)
			(stroke
				(width 0.1)
				(type default)
			)
			(layer "B.Fab")
		)
		(fp_line
			(start -0.299974 0.150114)
			(end 0.299974 0.150114)
			(stroke
				(width 0.1)
				(type default)
			)
			(layer "B.Fab")
		)
		(fp_line
			(start -0.299974 -0.150114)
			(end -0.299974 0.150114)
			(stroke
				(width 0.1)
				(type default)
			)
			(layer "B.Fab")
		)
		(pad "1" smd rect
			(at 0.2667 0)
			(size 0.3048 0.381)
			(layers "B.Cu" "B.Mask" "B.Paste")
			(net "P1V8_PEX")
		)
		(pad "2" smd rect
			(at -0.2667 0)
			(size 0.3048 0.381)
			(layers "B.Cu" "B.Mask" "B.Paste")
			(net "GND")
		)
	)
	(footprint ""
		(layer "B.Cu")
		(at 232.397046 -154.143202 -90)
		(property "Reference" "C2785"
			(at 0 0 90)
			(layer "B.SilkS")
			(hide yes)
			(effects
				(font
					(size 1.27 1.27)
				)
				(justify mirror)
			)
		)
		(property "Value" ""
			(at 0 0 90)
			(layer "B.Fab")
			(effects
				(font
					(size 1.27 1.27)
				)
				(justify mirror)
			)
		)
		(duplicate_pad_numbers_are_jumpers no)
		(fp_line
			(start -1.2954 0.5842)
			(end 1.2954 0.5842)
			(stroke
				(width 0.1524)
				(type default)
			)
			(layer "B.SilkS")
		)
		(fp_line
			(start 1.2954 0.5842)
			(end 1.2954 -0.5842)
			(stroke
				(width 0.1524)
				(type default)
			)
			(layer "B.SilkS")
		)
		(fp_line
			(start -1.2954 -0.5842)
			(end -1.2954 0.5842)
			(stroke
				(width 0.1524)
				(type default)
			)
			(layer "B.SilkS")
		)
		(fp_line
			(start 1.2954 -0.5842)
			(end -1.2954 -0.5842)
			(stroke
				(width 0.1524)
				(type default)
			)
			(layer "B.SilkS")
		)
		(fp_line
			(start -0.8636 0.4572)
			(end 0.8636 0.4572)
			(stroke
				(width 0.1)
				(type default)
			)
			(layer "B.Fab")
		)
		(fp_line
			(start 0.8636 0.4572)
			(end 0.8636 0.4064)
			(stroke
				(width 0.1)
				(type default)
			)
			(layer "B.Fab")
		)
		(fp_line
			(start -1.1938 0.4064)
			(end -0.8636 0.4064)
			(stroke
				(width 0.1)
				(type default)
			)
			(layer "B.Fab")
		)
		(fp_line
			(start -0.8636 0.4064)
			(end -0.8636 0.4572)
			(stroke
				(width 0.1)
				(type default)
			)
			(layer "B.Fab")
		)
		(fp_line
			(start 0.8636 0.4064)
			(end 1.1938 0.4064)
			(stroke
				(width 0.1)
				(type default)
			)
			(layer "B.Fab")
		)
		(fp_line
			(start 1.1938 0.4064)
			(end 1.1938 -0.4064)
			(stroke
				(width 0.1)
				(type default)
			)
			(layer "B.Fab")
		)
		(fp_line
			(start -1.1938 -0.4064)
			(end -1.1938 0.4064)
			(stroke
				(width 0.1)
				(type default)
			)
			(layer "B.Fab")
		)
		(fp_line
			(start -0.8636 -0.4064)
			(end -1.1938 -0.4064)
			(stroke
				(width 0.1)
				(type default)
			)
			(layer "B.Fab")
		)
		(fp_line
			(start 0.8636 -0.4064)
			(end 0.8636 -0.4572)
			(stroke
				(width 0.1)
				(type default)
			)
			(layer "B.Fab")
		)
		(fp_line
			(start 1.1938 -0.4064)
			(end 0.8636 -0.4064)
			(stroke
				(width 0.1)
				(type default)
			)
			(layer "B.Fab")
		)
		(fp_line
			(start -0.8636 -0.4572)
			(end -0.8636 -0.4064)
			(stroke
				(width 0.1)
				(type default)
			)
			(layer "B.Fab")
		)
		(fp_line
			(start 0.8636 -0.4572)
			(end -0.8636 -0.4572)
			(stroke
				(width 0.1)
				(type default)
			)
			(layer "B.Fab")
		)
		(pad "1" smd rect
			(at 0.7366 0 180)
			(size 0.7112 0.8128)
			(layers "B.Cu" "B.Mask" "B.Paste")
			(net "P3V3_CLK_GEN_VDD_CK440_PEX")
		)
		(pad "2" smd rect
			(at -0.7366 0 180)
			(size 0.7112 0.8128)
			(layers "B.Cu" "B.Mask" "B.Paste")
			(net "GND")
		)
	)
	(footprint ""
		(layer "B.Cu")
		(at 55.849774 -292.099746 90)
		(property "Reference" "C1201"
			(at 0 0 90)
			(layer "B.SilkS")
			(hide yes)
			(effects
				(font
					(size 1.27 1.27)
				)
				(justify mirror)
			)
		)
		(property "Value" ""
			(at 0 0 90)
			(layer "B.Fab")
			(effects
				(font
					(size 1.27 1.27)
				)
				(justify mirror)
			)
		)
		(duplicate_pad_numbers_are_jumpers no)
		(fp_line
			(start 0.299974 -0.150114)
			(end -0.299974 -0.150114)
			(stroke
				(width 0.1)
				(type default)
			)
			(layer "B.Fab")
		)
		(fp_line
			(start -0.299974 -0.150114)
			(end -0.299974 0.150114)
			(stroke
				(width 0.1)
				(type default)
			)
			(layer "B.Fab")
		)
		(fp_line
			(start 0.299974 0.150114)
			(end 0.299974 -0.150114)
			(stroke
				(width 0.1)
				(type default)
			)
			(layer "B.Fab")
		)
		(fp_line
			(start -0.299974 0.150114)
			(end 0.299974 0.150114)
			(stroke
				(width 0.1)
				(type default)
			)
			(layer "B.Fab")
		)
		(pad "1" smd rect
			(at 0.2667 0 270)
			(size 0.3048 0.381)
			(layers "B.Cu" "B.Mask" "B.Paste")
			(net "P0V8_SERDES_VDDA_PEX0")
		)
		(pad "2" smd rect
			(at -0.2667 0 270)
			(size 0.3048 0.381)
			(layers "B.Cu" "B.Mask" "B.Paste")
			(net "GND")
		)
	)
	(footprint ""
		(layer "B.Cu")
		(at 351.926906 -308.613556 90)
		(property "Reference" "C1923"
			(at 0 0 90)
			(layer "B.SilkS")
			(hide yes)
			(effects
				(font
					(size 1.27 1.27)
				)
				(justify mirror)
			)
		)
		(property "Value" ""
			(at 0 0 90)
			(layer "B.Fab")
			(effects
				(font
					(size 1.27 1.27)
				)
				(justify mirror)
			)
		)
		(duplicate_pad_numbers_are_jumpers no)
		(fp_line
			(start 1.2954 -0.5842)
			(end -1.2954 -0.5842)
			(stroke
				(width 0.1524)
				(type default)
			)
			(layer "B.SilkS")
		)
		(fp_line
			(start -1.2954 -0.5842)
			(end -1.2954 0.5842)
			(stroke
				(width 0.1524)
				(type default)
			)
			(layer "B.SilkS")
		)
		(fp_line
			(start 1.2954 0.5842)
			(end 1.2954 -0.5842)
			(stroke
				(width 0.1524)
				(type default)
			)
			(layer "B.SilkS")
		)
		(fp_line
			(start -1.2954 0.5842)
			(end 1.2954 0.5842)
			(stroke
				(width 0.1524)
				(type default)
			)
			(layer "B.SilkS")
		)
		(fp_line
			(start 0.8636 -0.4572)
			(end -0.8636 -0.4572)
			(stroke
				(width 0.1)
				(type default)
			)
			(layer "B.Fab")
		)
		(fp_line
			(start -0.8636 -0.4572)
			(end -0.8636 -0.4064)
			(stroke
				(width 0.1)
				(type default)
			)
			(layer "B.Fab")
		)
		(fp_line
			(start 1.1938 -0.4064)
			(end 0.8636 -0.4064)
			(stroke
				(width 0.1)
				(type default)
			)
			(layer "B.Fab")
		)
		(fp_line
			(start 0.8636 -0.4064)
			(end 0.8636 -0.4572)
			(stroke
				(width 0.1)
				(type default)
			)
			(layer "B.Fab")
		)
		(fp_line
			(start -0.8636 -0.4064)
			(end -1.1938 -0.4064)
			(stroke
				(width 0.1)
				(type default)
			)
			(layer "B.Fab")
		)
		(fp_line
			(start -1.1938 -0.4064)
			(end -1.1938 0.4064)
			(stroke
				(width 0.1)
				(type default)
			)
			(layer "B.Fab")
		)
		(fp_line
			(start 1.1938 0.4064)
			(end 1.1938 -0.4064)
			(stroke
				(width 0.1)
				(type default)
			)
			(layer "B.Fab")
		)
		(fp_line
			(start 0.8636 0.4064)
			(end 1.1938 0.4064)
			(stroke
				(width 0.1)
				(type default)
			)
			(layer "B.Fab")
		)
		(fp_line
			(start -0.8636 0.4064)
			(end -0.8636 0.4572)
			(stroke
				(width 0.1)
				(type default)
			)
			(layer "B.Fab")
		)
		(fp_line
			(start -1.1938 0.4064)
			(end -0.8636 0.4064)
			(stroke
				(width 0.1)
				(type default)
			)
			(layer "B.Fab")
		)
		(fp_line
			(start 0.8636 0.4572)
			(end 0.8636 0.4064)
			(stroke
				(width 0.1)
				(type default)
			)
			(layer "B.Fab")
		)
		(fp_line
			(start -0.8636 0.4572)
			(end 0.8636 0.4572)
			(stroke
				(width 0.1)
				(type default)
			)
			(layer "B.Fab")
		)
		(pad "1" smd rect
			(at 0.7366 0)
			(size 0.7112 0.8128)
			(layers "B.Cu" "B.Mask" "B.Paste")
			(net "P0V8_SERDES_VDDA_PEX3")
		)
		(pad "2" smd rect
			(at -0.7366 0)
			(size 0.7112 0.8128)
			(layers "B.Cu" "B.Mask" "B.Paste")
			(net "GND")
		)
	)
	(footprint ""
		(layer "B.Cu")
		(at 415.101278 -305.399948 -90)
		(property "Reference" "C3484"
			(at 0 0 90)
			(layer "B.SilkS")
			(hide yes)
			(effects
				(font
					(size 1.27 1.27)
				)
				(justify mirror)
			)
		)
		(property "Value" ""
			(at 0 0 90)
			(layer "B.Fab")
			(effects
				(font
					(size 1.27 1.27)
				)
				(justify mirror)
			)
		)
		(duplicate_pad_numbers_are_jumpers no)
		(fp_line
			(start -0.299974 0.150114)
			(end 0.299974 0.150114)
			(stroke
				(width 0.1)
				(type default)
			)
			(layer "B.Fab")
		)
		(fp_line
			(start 0.299974 0.150114)
			(end 0.299974 -0.150114)
			(stroke
				(width 0.1)
				(type default)
			)
			(layer "B.Fab")
		)
		(fp_line
			(start -0.299974 -0.150114)
			(end -0.299974 0.150114)
			(stroke
				(width 0.1)
				(type default)
			)
			(layer "B.Fab")
		)
		(fp_line
			(start 0.299974 -0.150114)
			(end -0.299974 -0.150114)
			(stroke
				(width 0.1)
				(type default)
			)
			(layer "B.Fab")
		)
		(pad "1" smd rect
			(at 0.2667 0 90)
			(size 0.3048 0.381)
			(layers "B.Cu" "B.Mask" "B.Paste")
			(net "P1V25_SERDES_VDDPLL_PEX3")
		)
		(pad "2" smd rect
			(at -0.2667 0 90)
			(size 0.3048 0.381)
			(layers "B.Cu" "B.Mask" "B.Paste")
			(net "GND")
		)
	)
)
